# S9S_MB_2U (Grand Teton) — schematic netlist excerpt (pin names and nets, part order shuffled) for the footprints in the layout excerpt that follows; sources: Cadence DE-HDL packaged netlist, KiCad conversion of 03242023_DA0F0TMBIJ0_F0T_Motherboard_J_brd_V01_OCP.brd

J115  PICOPROBE_BXA  DELTA-L 4.0 EMPTY  pkg TRIANG_LAUNCH_3PXB  page 308
  \1_p\  = DELTA_L_85_5INCH_IN6_DP
  \2_n\  = DELTA_L_85_5INCH_IN6_DN
  \3_g\  = DELTA_L_GND_1

(kicad_pcb
	(version 20260206)
	(generator "pcbnew")
	(generator_version "10.0")
	(general
		(thickness 1.6)
		(legacy_teardrops no)
	)
	(paper "A4")
	(title_block
		(title "03242023_DA0F0TMBIJ0_F0T_Motherboard_J_brd_V01_OCP.brd")
		(comment 1 "Grand Teton / footprints 6001-6001 of 6105")
	)
	(layers
		(0 "F.Cu" signal "TOP")
		(4 "In1.Cu" signal "GND")
		(6 "In2.Cu" signal "IN1")
		(8 "In3.Cu" signal "GND1")
		(10 "In4.Cu" signal "IN2")
		(12 "In5.Cu" signal "GND2")
		(14 "In6.Cu" signal "IN3")
		(16 "In7.Cu" signal "GND3")
		(18 "In8.Cu" signal "VCC")
		(20 "In9.Cu" signal "VCC1")
		(22 "In10.Cu" signal "GND4")
		(24 "In11.Cu" signal "IN4")
		(26 "In12.Cu" signal "GND5")
		(28 "In13.Cu" signal "IN5")
		(30 "In14.Cu" signal "GND6")
		(32 "In15.Cu" signal "IN6")
		(34 "In16.Cu" signal "GND7")
		(2 "B.Cu" signal "BOTTOM")
		(9 "F.Adhes" user "F.Adhesive")
		(11 "B.Adhes" user "B.Adhesive")
		(13 "F.Paste" user "Package Geometry/Pastemask Top")
		(15 "B.Paste" user "Package Geometry/Pastemask Bottom")
		(5 "F.SilkS" user "Ref Des/Silkscreen Top")
		(7 "B.SilkS" user "Ref Des/Silkscreen Bottom")
		(1 "F.Mask" user "Board Geometry/Soldermask Top")
		(3 "B.Mask" user "Board Geometry/Soldermask Bottom")
		(17 "Dwgs.User" user "User.Drawings")
		(19 "Cmts.User" user "User.Comments")
		(21 "Eco1.User" user "User.Eco1")
		(23 "Eco2.User" user "User.Eco2")
		(25 "Edge.Cuts" user "Board Geometry/Outline")
		(27 "Margin" user)
		(31 "F.CrtYd" user "Package Geometry/Place Bound Top")
		(29 "B.CrtYd" user "Package Geometry/Place Bound Bottom")
		(35 "F.Fab" user "Ref Des/Assembly Top")
		(33 "B.Fab" user "Ref Des/Assembly Bottom")
	)
	(footprint ""
		(layer "B.Cu")
		(at 339.298534 2.923794 180)
		(property "Reference" "J115"
			(at 4.172204 -1.521206 270)
			(unlocked yes)
			(layer "B.SilkS")
			(effects
				(font
					(size 0.7874 0.5842)
					(thickness 0.1524)
				)
				(justify left mirror)
			)
		)
		(property "Value" ""
			(at 0 0 0)
			(layer "B.Fab")
			(effects
				(font
					(size 1.27 1.27)
				)
				(justify mirror)
			)
		)
		(duplicate_pad_numbers_are_jumpers no)
		(fp_line
			(start 1.2192 2.1082)
			(end 1.2192 -2.1082)
			(stroke
				(width 0.1524)
				(type default)
			)
			(layer "B.SilkS")
		)
		(fp_line
			(start 1.2192 -2.1082)
			(end -1.2192 -2.1082)
			(stroke
				(width 0.1524)
				(type default)
			)
			(layer "B.SilkS")
		)
		(fp_line
			(start -1.2192 2.1082)
			(end 1.2192 2.1082)
			(stroke
				(width 0.1524)
				(type default)
			)
			(layer "B.SilkS")
		)
		(fp_line
			(start -1.2192 -2.1082)
			(end -1.2192 2.1082)
			(stroke
				(width 0.1524)
				(type default)
			)
			(layer "B.SilkS")
		)
		(pad "" np_thru_hole circle
			(at -3.4671 -1.27 90)
			(size 1.0414 1.0414)
			(drill 1.0414)
			(layers "*.Cu" "*.Mask")
			(clearance 0.381)
			(thermal_gap 0.381)
		)
		(pad "" np_thru_hole circle
			(at -3.4671 1.27 90)
			(size 1.0414 1.0414)
			(drill 1.0414)
			(layers "*.Cu" "*.Mask")
			(clearance 0.381)
			(thermal_gap 0.381)
		)
		(pad "" np_thru_hole circle
			(at 2.8829 -1.27 90)
			(size 1.0414 1.0414)
			(drill 1.0414)
			(layers "*.Cu" "*.Mask")
			(clearance 0.381)
			(thermal_gap 0.381)
		)
		(pad "" np_thru_hole circle
			(at 2.8829 1.27 90)
			(size 1.0414 1.0414)
			(drill 1.0414)
			(layers "*.Cu" "*.Mask")
			(clearance 0.381)
			(thermal_gap 0.381)
		)
		(pad "1" smd rect
			(at -0.8255 -0.249936 90)
			(size 0.3048 0.508)
			(layers "B.Cu" "B.Mask" "B.Paste")
			(net "DELTA_L_85_5INCH_IN6_DP")
		)
		(pad "2" smd rect
			(at -0.8255 0.249936 90)
			(size 0.3048 0.508)
			(layers "B.Cu" "B.Mask" "B.Paste")
			(net "DELTA_L_85_5INCH_IN6_DN")
		)
		(pad "3" smd circle
			(at 0 0)
			(size 0 0)
			(layers "B.Cu" "B.Mask" "B.Paste")
			(net "DELTA_L_GND_1")
		)
		(zone
			(layers "F.Cu" "B.Cu" "In1.Cu" "In2.Cu" "In3.Cu" "In4.Cu" "In5.Cu" "In6.Cu"
				"In7.Cu" "In8.Cu" "In9.Cu" "In10.Cu" "In11.Cu" "In12.Cu" "In13.Cu" "In14.Cu"
				"In15.Cu" "In16.Cu"
			)
			(hatch none 0.5)
			(connect_pads
				(clearance 0)
			)
			(min_thickness 0.25)
			(keepout
				(tracks not_allowed)
				(vias allowed)
				(pads allowed)
				(copperpour not_allowed)
				(footprints allowed)
			)
			(placement
				(enabled no)
				(sheetname "")
			)
			(fill
				(thermal_gap 0.5)
				(thermal_bridge_width 0.5)
				(island_removal_mode 0)
			)
			(polygon
				(pts
					(arc
						(start 337.342734 1.653794)
						(mid 335.488534 1.653794)
						(end 337.342734 1.653794)
					)
				)
			)
		)
		(zone
			(layers "F.Cu" "B.Cu" "In1.Cu" "In2.Cu" "In3.Cu" "In4.Cu" "In5.Cu" "In6.Cu"
				"In7.Cu" "In8.Cu" "In9.Cu" "In10.Cu" "In11.Cu" "In12.Cu" "In13.Cu" "In14.Cu"
				"In15.Cu" "In16.Cu"
			)
			(hatch none 0.5)
			(connect_pads
				(clearance 0)
			)
			(min_thickness 0.25)
			(keepout
				(tracks not_allowed)
				(vias allowed)
				(pads allowed)
				(copperpour not_allowed)
				(footprints allowed)
			)
			(placement
				(enabled no)
				(sheetname "")
			)
			(fill
				(thermal_gap 0.5)
				(thermal_bridge_width 0.5)
				(island_removal_mode 0)
			)
			(polygon
				(pts
					(arc
						(start 337.342734 4.193794)
						(mid 335.488534 4.193794)
						(end 337.342734 4.193794)
					)
				)
			)
		)
		(zone
			(layers "F.Cu" "B.Cu" "In1.Cu" "In2.Cu" "In3.Cu" "In4.Cu" "In5.Cu" "In6.Cu"
				"In7.Cu" "In8.Cu" "In9.Cu" "In10.Cu" "In11.Cu" "In12.Cu" "In13.Cu" "In14.Cu"
				"In15.Cu" "In16.Cu"
			)
			(hatch none 0.5)
			(connect_pads
				(clearance 0)
			)
			(min_thickness 0.25)
			(keepout
				(tracks not_allowed)
				(vias allowed)
				(pads allowed)
				(copperpour not_allowed)
				(footprints allowed)
			)
			(placement
				(enabled no)
				(sheetname "")
			)
			(fill
				(thermal_gap 0.5)
				(thermal_bridge_width 0.5)
				(island_removal_mode 0)
			)
			(polygon
				(pts
					(arc
						(start 343.692734 1.653794)
						(mid 341.838534 1.653794)
						(end 343.692734 1.653794)
					)
				)
			)
		)
		(zone
			(layers "F.Cu" "B.Cu" "In1.Cu" "In2.Cu" "In3.Cu" "In4.Cu" "In5.Cu" "In6.Cu"
				"In7.Cu" "In8.Cu" "In9.Cu" "In10.Cu" "In11.Cu" "In12.Cu" "In13.Cu" "In14.Cu"
				"In15.Cu" "In16.Cu"
			)
			(hatch none 0.5)
			(connect_pads
				(clearance 0)
			)
			(min_thickness 0.25)
			(keepout
				(tracks not_allowed)
				(vias allowed)
				(pads allowed)
				(copperpour not_allowed)
				(footprints allowed)
			)
			(placement
				(enabled no)
				(sheetname "")
			)
			(fill
				(thermal_gap 0.5)
				(thermal_bridge_width 0.5)
				(island_removal_mode 0)
			)
			(polygon
				(pts
					(arc
						(start 343.692734 4.193794)
						(mid 341.838534 4.193794)
						(end 343.692734 4.193794)
					)
				)
			)
		)
		(zone
			(layer "B.Cu")
			(hatch none 0.5)
			(connect_pads
				(clearance 0)
			)
			(min_thickness 0.25)
			(keepout
				(tracks not_allowed)
				(vias allowed)
				(pads allowed)
				(copperpour not_allowed)
				(footprints allowed)
			)
			(placement
				(enabled no)
				(sheetname "")
			)
			(fill
				(thermal_gap 0.5)
				(thermal_bridge_width 0.5)
				(island_removal_mode 0)
			)
			(polygon
				(pts
					(xy 340.416134 3.472434) (xy 340.416134 3.37693) (xy 339.819234 3.37693) (xy 339.819234 2.97053)
					(xy 340.416134 2.97053) (xy 340.416134 2.877058) (xy 339.819234 2.877058) (xy 339.819234 2.470658)
					(xy 340.416134 2.470658) (xy 340.416134 2.375154) (xy 339.717634 2.375154) (xy 339.717634 3.472434)
				)
			)
		)
	)
)
